(kicad_pcb
	(version 20241229)
	(generator "pcbnew")
	(generator_version "9.0")
	(general
		(thickness 1.599998)
		(legacy_teardrops no)
	)
	(paper "A4")
	(title_block
		(title "Artix - Datacenter Secure Control Module (DC-SCM)")
		(date "2024-11-06")
		(rev "1.1.3")
		(comment 9 "footprints 378-382 of 544")
	)
	(layers
		(0 "F.Cu" signal)
		(4 "In1.Cu" signal)
		(6 "In2.Cu" signal)
		(8 "In3.Cu" signal)
		(10 "In4.Cu" signal)
		(12 "In5.Cu" signal)
		(14 "In6.Cu" signal)
		(2 "B.Cu" signal)
		(9 "F.Adhes" user "F.Adhesive")
		(11 "B.Adhes" user "B.Adhesive")
		(13 "F.Paste" user)
		(15 "B.Paste" user)
		(5 "F.SilkS" user "F.Silkscreen")
		(7 "B.SilkS" user "B.Silkscreen")
		(1 "F.Mask" user)
		(3 "B.Mask" user)
		(17 "Dwgs.User" user "User.Drawings")
		(19 "Cmts.User" user "User.Comments")
		(21 "Eco1.User" user "User.Eco1")
		(23 "Eco2.User" user "User.Eco2")
		(25 "Edge.Cuts" user)
		(27 "Margin" user)
		(31 "F.CrtYd" user "F.Courtyard")
		(29 "B.CrtYd" user "B.Courtyard")
		(35 "F.Fab" user)
		(33 "B.Fab" user)
	)
	(footprint "antmicro-footprints:C_0402_1005Metric"
		(layer "B.Cu")
		(at 126.95 113.465 -90)
		(descr "Capacitor SMD 0402")
		(tags "capacitor SMD 0402")
		(property "Reference" "C13"
			(at 0.825 -0.31375 90)
			(layer "B.SilkS")
			(effects
				(font
					(size 0.7 0.7)
					(thickness 0.15)
				)
				(justify left bottom mirror)
			)
		)
		(property "Value" "C_100n_0402"
			(at 0 -1.4 90)
			(layer "B.Fab")
			(effects
				(font
					(size 0.7 0.7)
					(thickness 0.15)
				)
				(justify left bottom mirror)
			)
		)
		(property "Datasheet" "https://www.murata.com/products/productdetail?partno=GRM155R61H104KE14%23"
			(at 0 0 270)
			(layer "F.Fab")
			(hide yes)
			(effects
				(font
					(size 1.27 1.27)
					(thickness 0.15)
				)
			)
		)
		(property "Description" "SMD Multilayer Ceramic Capacitor, 0.1 µF, 50 V, 0402 [1005 Metric], ± 10%, X5R, GRM Series"
			(at 0 0 270)
			(layer "F.Fab")
			(hide yes)
			(effects
				(font
					(size 1.27 1.27)
					(thickness 0.15)
				)
			)
		)
		(property "Author" "Antmicro"
			(at 13.485 240.415 0)
			(layer "B.Fab")
			(hide yes)
			(effects
				(font
					(size 1 1)
					(thickness 0.15)
				)
				(justify mirror)
			)
		)
		(property "Dielectric" "X5R"
			(at 13.485 240.415 0)
			(layer "B.Fab")
			(hide yes)
			(effects
				(font
					(size 1 1)
					(thickness 0.15)
				)
				(justify mirror)
			)
		)
		(property "License" "Apache-2.0"
			(at 13.485 240.415 0)
			(layer "B.Fab")
			(hide yes)
			(effects
				(font
					(size 1 1)
					(thickness 0.15)
				)
				(justify mirror)
			)
		)
		(property "MPN" "GRM155R61H104KE14D"
			(at 13.485 240.415 0)
			(layer "B.Fab")
			(hide yes)
			(effects
				(font
					(size 1 1)
					(thickness 0.15)
				)
				(justify mirror)
			)
		)
		(property "Manufacturer" "Murata"
			(at 13.485 240.415 0)
			(layer "B.Fab")
			(hide yes)
			(effects
				(font
					(size 1 1)
					(thickness 0.15)
				)
				(justify mirror)
			)
		)
		(property "Val" "100n"
			(at 13.485 240.415 0)
			(layer "B.Fab")
			(hide yes)
			(effects
				(font
					(size 1 1)
					(thickness 0.15)
				)
				(justify mirror)
			)
		)
		(property "Voltage" "50V"
			(at 13.485 240.415 0)
			(layer "B.Fab")
			(hide yes)
			(effects
				(font
					(size 1 1)
					(thickness 0.15)
				)
				(justify mirror)
			)
		)
		(sheetname "/Interfaces/")
		(sheetfile "interfaces.kicad_sch")
		(attr smd)
		(fp_rect
			(start -0.925 0.47)
			(end 0.925 -0.47)
			(stroke
				(width 0.05)
				(type default)
			)
			(fill no)
			(layer "B.CrtYd")
		)
		(fp_line
			(start -0.494 0.25)
			(end 0.504 0.25)
			(stroke
				(width 0.15)
				(type solid)
			)
			(layer "B.Fab")
		)
		(fp_line
			(start 0.504 0.25)
			(end 0.504 -0.248)
			(stroke
				(width 0.15)
				(type solid)
			)
			(layer "B.Fab")
		)
		(fp_line
			(start -0.494 -0.248)
			(end -0.494 0.25)
			(stroke
				(width 0.15)
				(type solid)
			)
			(layer "B.Fab")
		)
		(fp_line
			(start 0.504 -0.248)
			(end -0.494 -0.248)
			(stroke
				(width 0.15)
				(type solid)
			)
			(layer "B.Fab")
		)
		(pad "1" smd roundrect
			(at -0.48 0 270)
			(size 0.59 0.64)
			(layers "B.Cu" "B.Mask" "B.Paste")
			(roundrect_rratio 0.25)
			(net 1 "GND")
			(pintype "passive")
		)
		(pad "2" smd roundrect
			(at 0.48 0 270)
			(size 0.59 0.64)
			(layers "B.Cu" "B.Mask" "B.Paste")
			(roundrect_rratio 0.25)
			(net 2 "VCC3V3")
			(pintype "passive")
		)
	)
	(footprint "antmicro-footprints:C_0402_1005Metric"
		(layer "B.Cu")
		(at 139.774 125.514)
		(descr "Capacitor SMD 0402")
		(tags "capacitor SMD 0402")
		(property "Reference" "C18"
			(at 0.826 0.386 0)
			(layer "B.SilkS")
			(effects
				(font
					(size 0.7 0.7)
					(thickness 0.15)
				)
				(justify right bottom mirror)
			)
		)
		(property "Value" "C_100n_0402"
			(at 0 -1.4 0)
			(layer "B.Fab")
			(effects
				(font
					(size 0.7 0.7)
					(thickness 0.15)
				)
				(justify right bottom mirror)
			)
		)
		(property "Datasheet" "https://www.murata.com/products/productdetail?partno=GRM155R61H104KE14%23"
			(at 0 0 0)
			(layer "F.Fab")
			(hide yes)
			(effects
				(font
					(size 1.27 1.27)
					(thickness 0.15)
				)
			)
		)
		(property "Description" "SMD Multilayer Ceramic Capacitor, 0.1 µF, 50 V, 0402 [1005 Metric], ± 10%, X5R, GRM Series"
			(at 0 0 0)
			(layer "F.Fab")
			(hide yes)
			(effects
				(font
					(size 1.27 1.27)
					(thickness 0.15)
				)
			)
		)
		(property "Author" "Antmicro"
			(at 0 0 0)
			(layer "B.Fab")
			(hide yes)
			(effects
				(font
					(size 1 1)
					(thickness 0.15)
				)
				(justify mirror)
			)
		)
		(property "Dielectric" "X5R"
			(at 0 0 0)
			(layer "B.Fab")
			(hide yes)
			(effects
				(font
					(size 1 1)
					(thickness 0.15)
				)
				(justify mirror)
			)
		)
		(property "License" "Apache-2.0"
			(at 0 0 0)
			(layer "B.Fab")
			(hide yes)
			(effects
				(font
					(size 1 1)
					(thickness 0.15)
				)
				(justify mirror)
			)
		)
		(property "MPN" "GRM155R61H104KE14D"
			(at 0 0 0)
			(layer "B.Fab")
			(hide yes)
			(effects
				(font
					(size 1 1)
					(thickness 0.15)
				)
				(justify mirror)
			)
		)
		(property "Manufacturer" "Murata"
			(at 0 0 0)
			(layer "B.Fab")
			(hide yes)
			(effects
				(font
					(size 1 1)
					(thickness 0.15)
				)
				(justify mirror)
			)
		)
		(property "Val" "100n"
			(at 0 0 0)
			(layer "B.Fab")
			(hide yes)
			(effects
				(font
					(size 1 1)
					(thickness 0.15)
				)
				(justify mirror)
			)
		)
		(property "Voltage" "50V"
			(at 0 0 0)
			(layer "B.Fab")
			(hide yes)
			(effects
				(font
					(size 1 1)
					(thickness 0.15)
				)
				(justify mirror)
			)
		)
		(sheetname "/Interfaces/")
		(sheetfile "interfaces.kicad_sch")
		(attr smd)
		(fp_rect
			(start -0.925 0.47)
			(end 0.925 -0.47)
			(stroke
				(width 0.05)
				(type default)
			)
			(fill no)
			(layer "B.CrtYd")
		)
		(fp_line
			(start -0.494 -0.248)
			(end -0.494 0.25)
			(stroke
				(width 0.15)
				(type solid)
			)
			(layer "B.Fab")
		)
		(fp_line
			(start -0.494 0.25)
			(end 0.504 0.25)
			(stroke
				(width 0.15)
				(type solid)
			)
			(layer "B.Fab")
		)
		(fp_line
			(start 0.504 -0.248)
			(end -0.494 -0.248)
			(stroke
				(width 0.15)
				(type solid)
			)
			(layer "B.Fab")
		)
		(fp_line
			(start 0.504 0.25)
			(end 0.504 -0.248)
			(stroke
				(width 0.15)
				(type solid)
			)
			(layer "B.Fab")
		)
		(pad "1" smd roundrect
			(at -0.48 0)
			(size 0.59 0.64)
			(layers "B.Cu" "B.Mask" "B.Paste")
			(roundrect_rratio 0.25)
			(net 1 "GND")
			(pintype "passive")
		)
		(pad "2" smd roundrect
			(at 0.48 0)
			(size 0.59 0.64)
			(layers "B.Cu" "B.Mask" "B.Paste")
			(roundrect_rratio 0.25)
			(net 2 "VCC3V3")
			(pintype "passive")
		)
	)
	(footprint "antmicro-footprints:C_0402_1005Metric"
		(layer "B.Cu")
		(at 127.175 110.675)
		(descr "Capacitor SMD 0402")
		(tags "capacitor SMD 0402")
		(property "Reference" "C19"
			(at -1.075 -0.575 0)
			(layer "B.SilkS")
			(effects
				(font
					(size 0.7 0.7)
					(thickness 0.15)
				)
				(justify right bottom mirror)
			)
		)
		(property "Value" "C_100n_0402"
			(at 0 -1.4 0)
			(layer "B.Fab")
			(effects
				(font
					(size 0.7 0.7)
					(thickness 0.15)
				)
				(justify right bottom mirror)
			)
		)
		(property "Datasheet" "https://www.murata.com/products/productdetail?partno=GRM155R61H104KE14%23"
			(at 0 0 0)
			(layer "F.Fab")
			(hide yes)
			(effects
				(font
					(size 1.27 1.27)
					(thickness 0.15)
				)
			)
		)
		(property "Description" "SMD Multilayer Ceramic Capacitor, 0.1 µF, 50 V, 0402 [1005 Metric], ± 10%, X5R, GRM Series"
			(at 0 0 0)
			(layer "F.Fab")
			(hide yes)
			(effects
				(font
					(size 1.27 1.27)
					(thickness 0.15)
				)
			)
		)
		(property "Author" "Antmicro"
			(at 0 0 0)
			(layer "B.Fab")
			(hide yes)
			(effects
				(font
					(size 1 1)
					(thickness 0.15)
				)
				(justify mirror)
			)
		)
		(property "Dielectric" "X5R"
			(at 0 0 0)
			(layer "B.Fab")
			(hide yes)
			(effects
				(font
					(size 1 1)
					(thickness 0.15)
				)
				(justify mirror)
			)
		)
		(property "License" "Apache-2.0"
			(at 0 0 0)
			(layer "B.Fab")
			(hide yes)
			(effects
				(font
					(size 1 1)
					(thickness 0.15)
				)
				(justify mirror)
			)
		)
		(property "MPN" "GRM155R61H104KE14D"
			(at 0 0 0)
			(layer "B.Fab")
			(hide yes)
			(effects
				(font
					(size 1 1)
					(thickness 0.15)
				)
				(justify mirror)
			)
		)
		(property "Manufacturer" "Murata"
			(at 0 0 0)
			(layer "B.Fab")
			(hide yes)
			(effects
				(font
					(size 1 1)
					(thickness 0.15)
				)
				(justify mirror)
			)
		)
		(property "Val" "100n"
			(at 0 0 0)
			(layer "B.Fab")
			(hide yes)
			(effects
				(font
					(size 1 1)
					(thickness 0.15)
				)
				(justify mirror)
			)
		)
		(property "Voltage" "50V"
			(at 0 0 0)
			(layer "B.Fab")
			(hide yes)
			(effects
				(font
					(size 1 1)
					(thickness 0.15)
				)
				(justify mirror)
			)
		)
		(sheetname "/Interfaces/")
		(sheetfile "interfaces.kicad_sch")
		(attr smd)
		(fp_rect
			(start -0.925 0.47)
			(end 0.925 -0.47)
			(stroke
				(width 0.05)
				(type default)
			)
			(fill no)
			(layer "B.CrtYd")
		)
		(fp_line
			(start -0.494 -0.248)
			(end -0.494 0.25)
			(stroke
				(width 0.15)
				(type solid)
			)
			(layer "B.Fab")
		)
		(fp_line
			(start -0.494 0.25)
			(end 0.504 0.25)
			(stroke
				(width 0.15)
				(type solid)
			)
			(layer "B.Fab")
		)
		(fp_line
			(start 0.504 -0.248)
			(end -0.494 -0.248)
			(stroke
				(width 0.15)
				(type solid)
			)
			(layer "B.Fab")
		)
		(fp_line
			(start 0.504 0.25)
			(end 0.504 -0.248)
			(stroke
				(width 0.15)
				(type solid)
			)
			(layer "B.Fab")
		)
		(pad "1" smd roundrect
			(at -0.48 0)
			(size 0.59 0.64)
			(layers "B.Cu" "B.Mask" "B.Paste")
			(roundrect_rratio 0.25)
			(net 1 "GND")
			(pintype "passive")
		)
		(pad "2" smd roundrect
			(at 0.48 0)
			(size 0.59 0.64)
			(layers "B.Cu" "B.Mask" "B.Paste")
			(roundrect_rratio 0.25)
			(net 2 "VCC3V3")
			(pintype "passive")
		)
	)
	(footprint "antmicro-footprints:C_0402_1005Metric"
		(layer "B.Cu")
		(at 123 125.4 90)
		(descr "Capacitor SMD 0402")
		(tags "capacitor SMD 0402")
		(property "Reference" "C21"
			(at 0.8 0.4 90)
			(layer "B.SilkS")
			(effects
				(font
					(size 0.7 0.7)
					(thickness 0.15)
				)
				(justify right bottom mirror)
			)
		)
		(property "Value" "C_100n_0402"
			(at 0 -1.4 90)
			(layer "B.Fab")
			(effects
				(font
					(size 0.7 0.7)
					(thickness 0.15)
				)
				(justify right bottom mirror)
			)
		)
		(property "Datasheet" "https://www.murata.com/products/productdetail?partno=GRM155R61H104KE14%23"
			(at 0 0 90)
			(layer "F.Fab")
			(hide yes)
			(effects
				(font
					(size 1.27 1.27)
					(thickness 0.15)
				)
			)
		)
		(property "Description" "SMD Multilayer Ceramic Capacitor, 0.1 µF, 50 V, 0402 [1005 Metric], ± 10%, X5R, GRM Series"
			(at 0 0 90)
			(layer "F.Fab")
			(hide yes)
			(effects
				(font
					(size 1.27 1.27)
					(thickness 0.15)
				)
			)
		)
		(property "Author" "Antmicro"
			(at 248.4 2.4 0)
			(layer "B.Fab")
			(hide yes)
			(effects
				(font
					(size 1 1)
					(thickness 0.15)
				)
				(justify mirror)
			)
		)
		(property "Dielectric" "X5R"
			(at 248.4 2.4 0)
			(layer "B.Fab")
			(hide yes)
			(effects
				(font
					(size 1 1)
					(thickness 0.15)
				)
				(justify mirror)
			)
		)
		(property "License" "Apache-2.0"
			(at 248.4 2.4 0)
			(layer "B.Fab")
			(hide yes)
			(effects
				(font
					(size 1 1)
					(thickness 0.15)
				)
				(justify mirror)
			)
		)
		(property "MPN" "GRM155R61H104KE14D"
			(at 248.4 2.4 0)
			(layer "B.Fab")
			(hide yes)
			(effects
				(font
					(size 1 1)
					(thickness 0.15)
				)
				(justify mirror)
			)
		)
		(property "Manufacturer" "Murata"
			(at 248.4 2.4 0)
			(layer "B.Fab")
			(hide yes)
			(effects
				(font
					(size 1 1)
					(thickness 0.15)
				)
				(justify mirror)
			)
		)
		(property "Val" "100n"
			(at 248.4 2.4 0)
			(layer "B.Fab")
			(hide yes)
			(effects
				(font
					(size 1 1)
					(thickness 0.15)
				)
				(justify mirror)
			)
		)
		(property "Voltage" "50V"
			(at 248.4 2.4 0)
			(layer "B.Fab")
			(hide yes)
			(effects
				(font
					(size 1 1)
					(thickness 0.15)
				)
				(justify mirror)
			)
		)
		(sheetname "/Interfaces/")
		(sheetfile "interfaces.kicad_sch")
		(attr smd)
		(fp_rect
			(start -0.925 0.47)
			(end 0.925 -0.47)
			(stroke
				(width 0.05)
				(type default)
			)
			(fill no)
			(layer "B.CrtYd")
		)
		(fp_line
			(start 0.504 -0.248)
			(end -0.494 -0.248)
			(stroke
				(width 0.15)
				(type solid)
			)
			(layer "B.Fab")
		)
		(fp_line
			(start -0.494 -0.248)
			(end -0.494 0.25)
			(stroke
				(width 0.15)
				(type solid)
			)
			(layer "B.Fab")
		)
		(fp_line
			(start 0.504 0.25)
			(end 0.504 -0.248)
			(stroke
				(width 0.15)
				(type solid)
			)
			(layer "B.Fab")
		)
		(fp_line
			(start -0.494 0.25)
			(end 0.504 0.25)
			(stroke
				(width 0.15)
				(type solid)
			)
			(layer "B.Fab")
		)
		(pad "1" smd roundrect
			(at -0.48 0 90)
			(size 0.59 0.64)
			(layers "B.Cu" "B.Mask" "B.Paste")
			(roundrect_rratio 0.25)
			(net 1 "GND")
			(pintype "passive")
		)
		(pad "2" smd roundrect
			(at 0.48 0 90)
			(size 0.59 0.64)
			(layers "B.Cu" "B.Mask" "B.Paste")
			(roundrect_rratio 0.25)
			(net 2 "VCC3V3")
			(pintype "passive")
		)
	)
	(footprint "antmicro-footprints:C_0402_1005Metric"
		(layer "B.Cu")
		(at 121.875 109.36 90)
		(descr "Capacitor SMD 0402")
		(tags "capacitor SMD 0402")
		(property "Reference" "C23"
			(at 0.86 0.425 90)
			(layer "B.SilkS")
			(effects
				(font
					(size 0.7 0.7)
					(thickness 0.15)
				)
				(justify right bottom mirror)
			)
		)
		(property "Value" "C_4u7_0402"
			(at 0 -1.4 90)
			(layer "B.Fab")
			(effects
				(font
					(size 0.7 0.7)
					(thickness 0.15)
				)
				(justify right bottom mirror)
			)
		)
		(property "Datasheet" "https://www.murata.com/products/productdetail?partno=GRM155R61A475MEAA%23"
			(at 0 0 90)
			(layer "F.Fab")
			(hide yes)
			(effects
				(font
					(size 1.27 1.27)
					(thickness 0.15)
				)
			)
		)
		(property "Description" "SMD Multilayer Ceramic Capacitor, 4.7 µF, 10 V, 0402 [1005 Metric], ± 20%, X5R, GRM Series"
			(at 0 0 90)
			(layer "F.Fab")
			(hide yes)
			(effects
				(font
					(size 1.27 1.27)
					(thickness 0.15)
				)
			)
		)
		(property "Author" "Antmicro"
			(at 231.235 -12.515 0)
			(layer "B.Fab")
			(hide yes)
			(effects
				(font
					(size 1 1)
					(thickness 0.15)
				)
				(justify mirror)
			)
		)
		(property "Dielectric" ""
			(at 231.235 -12.515 0)
			(layer "B.Fab")
			(hide yes)
			(effects
				(font
					(size 1 1)
					(thickness 0.15)
				)
				(justify mirror)
			)
		)
		(property "License" "Apache-2.0"
			(at 231.235 -12.515 0)
			(layer "B.Fab")
			(hide yes)
			(effects
				(font
					(size 1 1)
					(thickness 0.15)
				)
				(justify mirror)
			)
		)
		(property "MPN" "GRM155R61A475MEAAD"
			(at 231.235 -12.515 0)
			(layer "B.Fab")
			(hide yes)
			(effects
				(font
					(size 1 1)
					(thickness 0.15)
				)
				(justify mirror)
			)
		)
		(property "Manufacturer" "Murata"
			(at 231.235 -12.515 0)
			(layer "B.Fab")
			(hide yes)
			(effects
				(font
					(size 1 1)
					(thickness 0.15)
				)
				(justify mirror)
			)
		)
		(property "Val" "4u7"
			(at 231.235 -12.515 0)
			(layer "B.Fab")
			(hide yes)
			(effects
				(font
					(size 1 1)
					(thickness 0.15)
				)
				(justify mirror)
			)
		)
		(property "Voltage" ""
			(at 231.235 -12.515 0)
			(layer "B.Fab")
			(hide yes)
			(effects
				(font
					(size 1 1)
					(thickness 0.15)
				)
				(justify mirror)
			)
		)
		(sheetname "/Interfaces/")
		(sheetfile "interfaces.kicad_sch")
		(attr smd)
		(fp_rect
			(start -0.925 0.47)
			(end 0.925 -0.47)
			(stroke
				(width 0.05)
				(type default)
			)
			(fill no)
			(layer "B.CrtYd")
		)
		(fp_line
			(start 0.504 -0.248)
			(end -0.494 -0.248)
			(stroke
				(width 0.15)
				(type solid)
			)
			(layer "B.Fab")
		)
		(fp_line
			(start -0.494 -0.248)
			(end -0.494 0.25)
			(stroke
				(width 0.15)
				(type solid)
			)
			(layer "B.Fab")
		)
		(fp_line
			(start 0.504 0.25)
			(end 0.504 -0.248)
			(stroke
				(width 0.15)
				(type solid)
			)
			(layer "B.Fab")
		)
		(fp_line
			(start -0.494 0.25)
			(end 0.504 0.25)
			(stroke
				(width 0.15)
				(type solid)
			)
			(layer "B.Fab")
		)
		(pad "1" smd roundrect
			(at -0.48 0 90)
			(size 0.59 0.64)
			(layers "B.Cu" "B.Mask" "B.Paste")
			(roundrect_rratio 0.25)
			(net 1 "GND")
			(pintype "passive")
		)
		(pad "2" smd roundrect
			(at 0.48 0 90)
			(size 0.59 0.64)
			(layers "B.Cu" "B.Mask" "B.Paste")
			(roundrect_rratio 0.25)
			(net 2 "VCC3V3")
			(pintype "passive")
		)
	)
)
